# S9S_MB_2U (Grand Teton) — schematic netlist excerpt (pin names and nets, part order shuffled) for the footprints in the layout excerpt that follows; sources: Cadence DE-HDL packaged netlist, KiCad conversion of 03242023_DA0F0TMBIJ0_F0T_Motherboard_J_brd_V01_OCP.brd

C993  Q_CAP  10UF 6.3V 20% X6S  pkg C0402  page 74 : A = PVCCIN_CPU0 ; B = GND
R4544  Q_RES  100K 1% EMPTY  pkg 0402LF  page 145 : A = HGX_DETECT_N ; B = GND

(kicad_pcb
	(version 20260206)
	(generator "pcbnew")
	(generator_version "10.0")
	(general
		(thickness 1.6)
		(legacy_teardrops no)
	)
	(paper "A4")
	(title_block
		(title "03242023_DA0F0TMBIJ0_F0T_Motherboard_J_brd_V01_OCP.brd")
		(comment 1 "Grand Teton / footprints 2979-2980 of 6105")
	)
	(layers
		(0 "F.Cu" signal "TOP")
		(4 "In1.Cu" signal "GND")
		(6 "In2.Cu" signal "IN1")
		(8 "In3.Cu" signal "GND1")
		(10 "In4.Cu" signal "IN2")
		(12 "In5.Cu" signal "GND2")
		(14 "In6.Cu" signal "IN3")
		(16 "In7.Cu" signal "GND3")
		(18 "In8.Cu" signal "VCC")
		(20 "In9.Cu" signal "VCC1")
		(22 "In10.Cu" signal "GND4")
		(24 "In11.Cu" signal "IN4")
		(26 "In12.Cu" signal "GND5")
		(28 "In13.Cu" signal "IN5")
		(30 "In14.Cu" signal "GND6")
		(32 "In15.Cu" signal "IN6")
		(34 "In16.Cu" signal "GND7")
		(2 "B.Cu" signal "BOTTOM")
		(9 "F.Adhes" user "F.Adhesive")
		(11 "B.Adhes" user "B.Adhesive")
		(13 "F.Paste" user "Package Geometry/Pastemask Top")
		(15 "B.Paste" user "Package Geometry/Pastemask Bottom")
		(5 "F.SilkS" user "Ref Des/Silkscreen Top")
		(7 "B.SilkS" user "Ref Des/Silkscreen Bottom")
		(1 "F.Mask" user "Board Geometry/Soldermask Top")
		(3 "B.Mask" user "Board Geometry/Soldermask Bottom")
		(17 "Dwgs.User" user "User.Drawings")
		(19 "Cmts.User" user "User.Comments")
		(21 "Eco1.User" user "User.Eco1")
		(23 "Eco2.User" user "User.Eco2")
		(25 "Edge.Cuts" user "Board Geometry/Outline")
		(27 "Margin" user)
		(31 "F.CrtYd" user "Package Geometry/Place Bound Top")
		(29 "B.CrtYd" user "Package Geometry/Place Bound Bottom")
		(35 "F.Fab" user "Ref Des/Assembly Top")
		(33 "B.Fab" user "Ref Des/Assembly Bottom")
	)
	(footprint ""
		(layer "F.Cu")
		(at 366.48263 -247.715024 90)
		(property "Reference" "C993"
			(at 0 0 90)
			(layer "F.SilkS")
			(hide yes)
			(effects
				(font
					(size 1.27 1.27)
				)
			)
		)
		(property "Value" ""
			(at 0 0 90)
			(layer "F.Fab")
			(effects
				(font
					(size 1.27 1.27)
				)
			)
		)
		(duplicate_pad_numbers_are_jumpers no)
		(fp_line
			(start 0.7874 -0.4064)
			(end 0.7874 0.4064)
			(stroke
				(width 0.1524)
				(type default)
			)
			(layer "F.SilkS")
		)
		(fp_line
			(start -0.7874 -0.4064)
			(end 0.7874 -0.4064)
			(stroke
				(width 0.1524)
				(type default)
			)
			(layer "F.SilkS")
		)
		(fp_line
			(start 0.7874 0.4064)
			(end -0.7874 0.4064)
			(stroke
				(width 0.1524)
				(type default)
			)
			(layer "F.SilkS")
		)
		(fp_line
			(start -0.7874 0.4064)
			(end -0.7874 -0.4064)
			(stroke
				(width 0.1524)
				(type default)
			)
			(layer "F.SilkS")
		)
		(fp_line
			(start -0.12065 -0.305054)
			(end -0.12065 -0.2794)
			(stroke
				(width 0.1)
				(type default)
			)
			(layer "F.Fab")
		)
		(fp_line
			(start -0.67945 -0.305054)
			(end -0.12065 -0.305054)
			(stroke
				(width 0.1)
				(type default)
			)
			(layer "F.Fab")
		)
		(fp_line
			(start 0.67945 -0.3048)
			(end 0.67945 0.3048)
			(stroke
				(width 0.1)
				(type default)
			)
			(layer "F.Fab")
		)
		(fp_line
			(start 0.12065 -0.3048)
			(end 0.67945 -0.3048)
			(stroke
				(width 0.1)
				(type default)
			)
			(layer "F.Fab")
		)
		(fp_line
			(start 0.12065 -0.2794)
			(end 0.12065 -0.3048)
			(stroke
				(width 0.1)
				(type default)
			)
			(layer "F.Fab")
		)
		(fp_line
			(start -0.12065 -0.2794)
			(end 0.12065 -0.2794)
			(stroke
				(width 0.1)
				(type default)
			)
			(layer "F.Fab")
		)
		(fp_line
			(start 0.120396 0.2794)
			(end -0.12065 0.2794)
			(stroke
				(width 0.1)
				(type default)
			)
			(layer "F.Fab")
		)
		(fp_line
			(start -0.12065 0.2794)
			(end -0.12065 0.3048)
			(stroke
				(width 0.1)
				(type default)
			)
			(layer "F.Fab")
		)
		(fp_line
			(start 0.67945 0.3048)
			(end 0.120396 0.3048)
			(stroke
				(width 0.1)
				(type default)
			)
			(layer "F.Fab")
		)
		(fp_line
			(start 0.120396 0.3048)
			(end 0.120396 0.2794)
			(stroke
				(width 0.1)
				(type default)
			)
			(layer "F.Fab")
		)
		(fp_line
			(start -0.12065 0.3048)
			(end -0.67945 0.3048)
			(stroke
				(width 0.1)
				(type default)
			)
			(layer "F.Fab")
		)
		(fp_line
			(start -0.67945 0.3048)
			(end -0.67945 -0.305054)
			(stroke
				(width 0.1)
				(type default)
			)
			(layer "F.Fab")
		)
		(pad "1" smd circle
			(at -0.40005 0 90)
			(size 0 0)
			(layers "F.Cu" "F.Mask" "F.Paste")
			(net "PVCCIN_CPU0")
		)
		(pad "2" smd circle
			(at 0.40005 0 90)
			(size 0 0)
			(layers "F.Cu" "F.Mask" "F.Paste")
			(net "GND")
		)
	)
	(footprint ""
		(layer "F.Cu")
		(at 98.1329 -413.273748)
		(property "Reference" "R4544"
			(at 0 0 0)
			(layer "F.SilkS")
			(hide yes)
			(effects
				(font
					(size 1.27 1.27)
				)
			)
		)
		(property "Value" ""
			(at 0 0 0)
			(layer "F.Fab")
			(effects
				(font
					(size 1.27 1.27)
				)
			)
		)
		(duplicate_pad_numbers_are_jumpers no)
		(fp_line
			(start -0.7874 -0.4064)
			(end 0.7874 -0.4064)
			(stroke
				(width 0.1524)
				(type default)
			)
			(layer "F.SilkS")
		)
		(fp_line
			(start -0.7874 0.4064)
			(end -0.7874 -0.4064)
			(stroke
				(width 0.1524)
				(type default)
			)
			(layer "F.SilkS")
		)
		(fp_line
			(start 0.7874 -0.4064)
			(end 0.7874 0.4064)
			(stroke
				(width 0.1524)
				(type default)
			)
			(layer "F.SilkS")
		)
		(fp_line
			(start 0.7874 0.4064)
			(end -0.7874 0.4064)
			(stroke
				(width 0.1524)
				(type default)
			)
			(layer "F.SilkS")
		)
		(fp_line
			(start -0.67945 -0.305054)
			(end -0.12065 -0.305054)
			(stroke
				(width 0.1)
				(type default)
			)
			(layer "F.Fab")
		)
		(fp_line
			(start -0.67945 0.3048)
			(end -0.67945 -0.305054)
			(stroke
				(width 0.1)
				(type default)
			)
			(layer "F.Fab")
		)
		(fp_line
			(start -0.12065 -0.305054)
			(end -0.12065 -0.2794)
			(stroke
				(width 0.1)
				(type default)
			)
			(layer "F.Fab")
		)
		(fp_line
			(start -0.12065 -0.2794)
			(end 0.12065 -0.2794)
			(stroke
				(width 0.1)
				(type default)
			)
			(layer "F.Fab")
		)
		(fp_line
			(start -0.12065 0.2794)
			(end -0.12065 0.3048)
			(stroke
				(width 0.1)
				(type default)
			)
			(layer "F.Fab")
		)
		(fp_line
			(start -0.12065 0.3048)
			(end -0.67945 0.3048)
			(stroke
				(width 0.1)
				(type default)
			)
			(layer "F.Fab")
		)
		(fp_line
			(start 0.120396 0.2794)
			(end -0.12065 0.2794)
			(stroke
				(width 0.1)
				(type default)
			)
			(layer "F.Fab")
		)
		(fp_line
			(start 0.120396 0.3048)
			(end 0.120396 0.2794)
			(stroke
				(width 0.1)
				(type default)
			)
			(layer "F.Fab")
		)
		(fp_line
			(start 0.12065 -0.3048)
			(end 0.67945 -0.3048)
			(stroke
				(width 0.1)
				(type default)
			)
			(layer "F.Fab")
		)
		(fp_line
			(start 0.12065 -0.2794)
			(end 0.12065 -0.3048)
			(stroke
				(width 0.1)
				(type default)
			)
			(layer "F.Fab")
		)
		(fp_line
			(start 0.67945 -0.3048)
			(end 0.67945 0.3048)
			(stroke
				(width 0.1)
				(type default)
			)
			(layer "F.Fab")
		)
		(fp_line
			(start 0.67945 0.3048)
			(end 0.120396 0.3048)
			(stroke
				(width 0.1)
				(type default)
			)
			(layer "F.Fab")
		)
		(pad "1" smd circle
			(at -0.40005 0)
			(size 0 0)
			(layers "F.Cu" "F.Mask" "F.Paste")
			(net "HGX_DETECT_N")
		)
		(pad "2" smd circle
			(at 0.40005 0)
			(size 0 0)
			(layers "F.Cu" "F.Mask" "F.Paste")
			(net "GND")
		)
	)
)
